(kicad_pcb
	(version 20241229)
	(generator "pcbnew")
	(generator_version "9.0")
	(general
		(thickness 1.711)
		(legacy_teardrops no)
	)
	(paper "A4")
	(title_block
		(title "Antmicro Baseboard for Jetson AGX Thor")
		(date "2026-02-18")
		(rev "1.1.0")
		(company "Antmicro Ltd")
		(comment 1 "www.antmicro.com")
		(comment 9 "footprints 269-269 of 1170")
	)
	(layers
		(0 "F.Cu" signal)
		(4 "In1.Cu" signal)
		(6 "In2.Cu" signal)
		(8 "In3.Cu" signal)
		(10 "In4.Cu" jumper)
		(12 "In5.Cu" signal)
		(14 "In6.Cu" signal)
		(16 "In7.Cu" signal)
		(18 "In8.Cu" signal)
		(2 "B.Cu" signal)
		(9 "F.Adhes" user "F.Adhesive")
		(11 "B.Adhes" user "B.Adhesive")
		(13 "F.Paste" user)
		(15 "B.Paste" user)
		(5 "F.SilkS" user "F.Silkscreen")
		(7 "B.SilkS" user "B.Silkscreen")
		(1 "F.Mask" user)
		(3 "B.Mask" user)
		(17 "Dwgs.User" user "User.Drawings")
		(19 "Cmts.User" user "User.Comments")
		(21 "Eco1.User" user "User.Eco1")
		(23 "Eco2.User" user "User.Eco2")
		(25 "Edge.Cuts" user)
		(27 "Margin" user)
		(31 "F.CrtYd" user "F.Courtyard")
		(29 "B.CrtYd" user "B.Courtyard")
		(35 "F.Fab" user)
		(33 "B.Fab" user)
	)
	(footprint "antmicro-footprints:SOT-23-8"
		(layer "F.Cu")
		(at 102.74 56.53 180)
		(descr "http://www.ti.com/lit/ds/symlink/ina219.pdf")
		(property "Reference" "U76"
			(at 1.06 2.33 0)
			(layer "F.SilkS")
			(effects
				(font
					(size 0.7 0.7)
					(thickness 0.15)
				)
				(justify right top)
			)
		)
		(property "Value" "INA219AIDCNR"
			(at -2.925 2.8 0)
			(layer "F.Fab")
			(effects
				(font
					(size 0.7 0.7)
					(thickness 0.15)
				)
				(justify right top)
			)
		)
		(property "Datasheet" "https://www.ti.com/lit/ds/symlink/ina219.pdf?ts=1713856455637&ref_url=https%253A%252F%252Fwww.mouser.es%252F"
			(at 0 0 0)
			(layer "F.Fab")
			(hide yes)
			(effects
				(font
					(size 1.27 1.27)
					(thickness 0.15)
				)
			)
		)
		(property "Description" "Zerø-Drift, Bidirectional Current/Power Monitor With I2C Interface"
			(at 0 0 0)
			(layer "F.Fab")
			(hide yes)
			(effects
				(font
					(size 1.27 1.27)
					(thickness 0.15)
				)
			)
		)
		(property "Manufacturer" "Texas Instruments"
			(at 0 0 180)
			(unlocked yes)
			(layer "F.Fab")
			(hide yes)
			(effects
				(font
					(size 1 1)
					(thickness 0.15)
				)
			)
		)
		(property "MPN" "INA219AIDCNR"
			(at 0 0 180)
			(unlocked yes)
			(layer "F.Fab")
			(hide yes)
			(effects
				(font
					(size 1 1)
					(thickness 0.15)
				)
			)
		)
		(property "Author" "Antmicro"
			(at 0 0 180)
			(unlocked yes)
			(layer "F.Fab")
			(hide yes)
			(effects
				(font
					(size 1 1)
					(thickness 0.15)
				)
			)
		)
		(property "License" "Apache-2.0"
			(at 0 0 180)
			(unlocked yes)
			(layer "F.Fab")
			(hide yes)
			(effects
				(font
					(size 1 1)
					(thickness 0.15)
				)
			)
		)
		(sheetname "/DCDC/")
		(sheetfile "dcdc.kicad_sch")
		(attr smd)
		(fp_line
			(start 1 1.6)
			(end 0.6 1.6)
			(stroke
				(width 0.15)
				(type solid)
			)
			(layer "F.SilkS")
		)
		(fp_line
			(start 1 1.3)
			(end 1 1.6)
			(stroke
				(width 0.15)
				(type solid)
			)
			(layer "F.SilkS")
		)
		(fp_line
			(start 1 -1.3)
			(end 1 -1.6)
			(stroke
				(width 0.15)
				(type solid)
			)
			(layer "F.SilkS")
		)
		(fp_line
			(start 1 -1.6)
			(end 0.625 -1.6)
			(stroke
				(width 0.15)
				(type solid)
			)
			(layer "F.SilkS")
		)
		(fp_line
			(start -0.613 1.6)
			(end -0.987 1.6)
			(stroke
				(width 0.15)
				(type solid)
			)
			(layer "F.SilkS")
		)
		(fp_line
			(start -0.987 1.6)
			(end -0.987 1.324)
			(stroke
				(width 0.15)
				(type solid)
			)
			(layer "F.SilkS")
		)
		(fp_line
			(start -1 -1.3)
			(end -1 -1.6)
			(stroke
				(width 0.15)
				(type solid)
			)
			(layer "F.SilkS")
		)
		(fp_line
			(start -1 -1.6)
			(end -0.6 -1.6)
			(stroke
				(width 0.15)
				(type solid)
			)
			(layer "F.SilkS")
		)
		(fp_circle
			(center -1.3 -1.4)
			(end -1.25 -1.4)
			(stroke
				(width 0.15)
				(type solid)
			)
			(fill yes)
			(layer "F.SilkS")
		)
		(fp_poly
			(pts
				(xy -1.9 -1.75) (xy 1.898 -1.75) (xy 1.898 1.75) (xy -1.9 1.75)
			)
			(stroke
				(width 0.05)
				(type solid)
			)
			(fill no)
			(layer "F.CrtYd")
		)
		(fp_line
			(start -1.4 -1.25)
			(end -1.2 -1.45)
			(stroke
				(width 0.15)
				(type solid)
			)
			(layer "F.Fab")
		)
		(fp_poly
			(pts
				(xy -1.401 -1.45) (xy 1.398 -1.45) (xy 1.398 1.449) (xy -1.401 1.449)
			)
			(stroke
				(width 0.15)
				(type solid)
			)
			(fill no)
			(layer "F.Fab")
		)
		(fp_text user "${REFERENCE}"
			(at -2.925 4.8 0)
			(layer "F.Fab")
			(effects
				(font
					(size 0.7 0.7)
					(thickness 0.15)
				)
				(justify right top)
			)
		)
		(fp_text user "License: Apache-2.0"
			(at -2.925 6 0)
			(layer "F.Fab")
			(effects
				(font
					(size 0.7 0.7)
					(thickness 0.15)
				)
				(justify right top)
			)
		)
		(fp_text user "Author: Antmicro"
			(at -2.925 7.2 0)
			(layer "F.Fab")
			(effects
				(font
					(size 0.7 0.7)
					(thickness 0.15)
				)
				(justify right top)
			)
		)
		(pad "1" smd roundrect
			(at -1.3 -0.975 90)
			(size 0.45 1.1)
			(layers "F.Cu" "F.Mask" "F.Paste")
			(roundrect_rratio 0.25)
			(net 1280 "Net-(U76-IN+)")
			(pinfunction "IN+")
			(pintype "passive")
		)
		(pad "2" smd roundrect
			(at -1.3 -0.325 90)
			(size 0.45 1.1)
			(layers "F.Cu" "F.Mask" "F.Paste")
			(roundrect_rratio 0.25)
			(net 1279 "Net-(U76-IN-)")
			(pinfunction "IN-")
			(pintype "passive")
		)
		(pad "3" smd roundrect
			(at -1.3 0.325 90)
			(size 0.45 1.1)
			(layers "F.Cu" "F.Mask" "F.Paste")
			(roundrect_rratio 0.25)
			(net 1 "GND")
			(pinfunction "GND")
			(pintype "power_in")
		)
		(pad "4" smd roundrect
			(at -1.3 0.975 90)
			(size 0.45 1.1)
			(layers "F.Cu" "F.Mask" "F.Paste")
			(roundrect_rratio 0.25)
			(net 4 "+3V3_AON")
			(pinfunction "V_{S}")
			(pintype "power_in")
		)
		(pad "5" smd roundrect
			(at 1.3 0.975 90)
			(size 0.45 1.1)
			(layers "F.Cu" "F.Mask" "F.Paste")
			(roundrect_rratio 0.25)
			(net 853 "/I2C_{SYS}.SCL")
			(pinfunction "SCL")
			(pintype "open_collector")
		)
		(pad "6" smd roundrect
			(at 1.3 0.325 90)
			(size 0.45 1.1)
			(layers "F.Cu" "F.Mask" "F.Paste")
			(roundrect_rratio 0.25)
			(net 850 "/I2C_{SYS}.SDA")
			(pinfunction "SDA")
			(pintype "open_collector")
		)
		(pad "7" smd roundrect
			(at 1.3 -0.325 90)
			(size 0.45 1.1)
			(layers "F.Cu" "F.Mask" "F.Paste")
			(roundrect_rratio 0.25)
			(net 850 "/I2C_{SYS}.SDA")
			(pinfunction "A0")
			(pintype "passive")
		)
		(pad "8" smd roundrect
			(at 1.3 -0.975 90)
			(size 0.45 1.1)
			(layers "F.Cu" "F.Mask" "F.Paste")
			(roundrect_rratio 0.25)
			(net 4 "+3V3_AON")
			(pinfunction "A1")
			(pintype "passive")
		)
	)
)
